(kicad_pcb
	(version 20260206)
	(generator "pcbnew")
	(generator_version "10.0")
	(general
		(thickness 1.6)
		(legacy_teardrops no)
	)
	(paper "A4")
	(title_block
		(title "pdpb — Lightning_PDPB_BRD.brd")
		(comment 1 "Lightning (Wiwynn / Facebook NVMe JBOF) / footprints 1027-1033 of 1140")
	)
	(layers
		(0 "F.Cu" signal "TOP")
		(4 "In1.Cu" signal "L2GND")
		(6 "In2.Cu" signal "L3")
		(8 "In3.Cu" signal "L4VCC")
		(10 "In4.Cu" signal "L5VCC")
		(12 "In5.Cu" signal "L6")
		(14 "In6.Cu" signal "L7GND")
		(2 "B.Cu" signal "BOTTOM")
		(9 "F.Adhes" user "F.Adhesive")
		(11 "B.Adhes" user "B.Adhesive")
		(13 "F.Paste" user "Package Geometry/Pastemask Top")
		(15 "B.Paste" user "Package Geometry/Pastemask Bottom")
		(5 "F.SilkS" user "Ref Des/Silkscreen Top")
		(7 "B.SilkS" user "Ref Des/Silkscreen Bottom")
		(1 "F.Mask" user "Board Geometry/Soldermask Top")
		(3 "B.Mask" user "Board Geometry/Soldermask Bottom")
		(17 "Dwgs.User" user "User.Drawings")
		(19 "Cmts.User" user "User.Comments")
		(21 "Eco1.User" user "User.Eco1")
		(23 "Eco2.User" user "User.Eco2")
		(25 "Edge.Cuts" user "Board Geometry/Outline")
		(27 "Margin" user)
		(31 "F.CrtYd" user "Package Geometry/Place Bound Top")
		(29 "B.CrtYd" user "Package Geometry/Place Bound Bottom")
		(35 "F.Fab" user "Ref Des/Assembly Top")
		(33 "B.Fab" user "Ref Des/Assembly Bottom")
	)
	(footprint ""
		(layer "F.Cu")
		(at 45.339 -244.729 -90)
		(property "Reference" "R9829"
			(at 0 0 270)
			(layer "F.SilkS")
			(hide yes)
			(effects
				(font
					(size 1.27 1.27)
				)
			)
		)
		(property "Value" "0R2J-2-GP"
			(at 0.064008 -3.993896 270)
			(unlocked yes)
			(layer "F.Fab")
			(hide yes)
			(effects
				(font
					(size 1.016 1.016)
					(thickness 0.1524)
				)
			)
		)
		(property "Device Type" "R402H16"
			(at 0.064008 -5.517896 270)
			(unlocked yes)
			(layer "F.Fab")
			(hide yes)
			(effects
				(font
					(size 1.016 1.016)
					(thickness 0.1524)
				)
			)
		)
		(duplicate_pad_numbers_are_jumpers no)
		(fp_line
			(start -0.508 -0.9398)
			(end -0.508 0.9398)
			(stroke
				(width 0.1524)
				(type default)
			)
			(layer "F.SilkS")
		)
		(fp_line
			(start 0.508 -0.9398)
			(end -0.508 -0.9398)
			(stroke
				(width 0.1524)
				(type default)
			)
			(layer "F.SilkS")
		)
		(fp_rect
			(start -0.508 0.9398)
			(end 0.508 -0.9398)
			(stroke
				(width 0)
				(type default)
			)
			(fill no)
			(layer "F.CrtYd")
		)
		(fp_rect
			(start -0.508 0.9398)
			(end 0.508 -0.9398)
			(stroke
				(width 0)
				(type default)
			)
			(fill no)
			(layer "F.Fab")
		)
		(pad "1" smd custom
			(at 0 -0.4445 270)
			(size 0.1397 0.1397)
			(layers "F.Cu" "F.Mask" "F.Paste")
			(net "ATTN_LED_DR7_AND")
			(options
				(clearance outline)
				(anchor circle)
			)
			(primitives
				(gr_poly
					(pts
						(arc
							(start -0.1778 -0.2794)
							(mid -0.249642 -0.249642)
							(end -0.2794 -0.1778)
						)
						(arc
							(start -0.2794 0.1778)
							(mid -0.249642 0.249642)
							(end -0.1778 0.2794)
						)
						(arc
							(start 0.1778 0.2794)
							(mid 0.249642 0.249642)
							(end 0.2794 0.1778)
						)
						(arc
							(start 0.2794 -0.1778)
							(mid 0.249642 -0.249642)
							(end 0.1778 -0.2794)
						)
					)
					(width 0)
					(fill yes)
				)
			)
		)
		(pad "2" smd custom
			(at 0 0.4445 270)
			(size 0.1397 0.1397)
			(layers "F.Cu" "F.Mask" "F.Paste")
			(net "ATTN_LED_DR7_AND_R")
			(options
				(clearance outline)
				(anchor circle)
			)
			(primitives
				(gr_poly
					(pts
						(arc
							(start -0.1778 -0.2794)
							(mid -0.249642 -0.249642)
							(end -0.2794 -0.1778)
						)
						(arc
							(start -0.2794 0.1778)
							(mid -0.249642 0.249642)
							(end -0.1778 0.2794)
						)
						(arc
							(start 0.1778 0.2794)
							(mid 0.249642 0.249642)
							(end 0.2794 0.1778)
						)
						(arc
							(start 0.2794 -0.1778)
							(mid 0.249642 -0.249642)
							(end 0.1778 -0.2794)
						)
					)
					(width 0)
					(fill yes)
				)
			)
		)
	)
	(footprint ""
		(layer "F.Cu")
		(at 90.17 -445.262)
		(property "Reference" "R9598"
			(at 0 0 0)
			(layer "F.SilkS")
			(hide yes)
			(effects
				(font
					(size 1.27 1.27)
				)
			)
		)
		(property "Value" "10R2F-L-GP"
			(at 0.064008 -3.993896 0)
			(unlocked yes)
			(layer "F.Fab")
			(hide yes)
			(effects
				(font
					(size 1.016 1.016)
					(thickness 0.1524)
				)
			)
		)
		(property "Device Type" "R402H14"
			(at 0.064008 -5.517896 0)
			(unlocked yes)
			(layer "F.Fab")
			(hide yes)
			(effects
				(font
					(size 1.016 1.016)
					(thickness 0.1524)
				)
			)
		)
		(duplicate_pad_numbers_are_jumpers no)
		(fp_line
			(start -0.508 -0.9398)
			(end -0.508 0.9398)
			(stroke
				(width 0.1524)
				(type default)
			)
			(layer "F.SilkS")
		)
		(fp_line
			(start 0.508 -0.9398)
			(end -0.508 -0.9398)
			(stroke
				(width 0.1524)
				(type default)
			)
			(layer "F.SilkS")
		)
		(fp_rect
			(start -0.508 0.9398)
			(end 0.508 -0.9398)
			(stroke
				(width 0)
				(type default)
			)
			(fill no)
			(layer "F.CrtYd")
		)
		(fp_rect
			(start -0.508 0.9398)
			(end 0.508 -0.9398)
			(stroke
				(width 0)
				(type default)
			)
			(fill no)
			(layer "F.Fab")
		)
		(pad "1" smd custom
			(at 0 -0.4445)
			(size 0.1397 0.1397)
			(layers "F.Cu" "F.Mask" "F.Paste")
			(net "SSD_PRSNT_NET5")
			(options
				(clearance outline)
				(anchor circle)
			)
			(primitives
				(gr_poly
					(pts
						(arc
							(start -0.1778 -0.2794)
							(mid -0.249642 -0.249642)
							(end -0.2794 -0.1778)
						)
						(arc
							(start -0.2794 0.1778)
							(mid -0.249642 0.249642)
							(end -0.1778 0.2794)
						)
						(arc
							(start 0.1778 0.2794)
							(mid 0.249642 0.249642)
							(end 0.2794 0.1778)
						)
						(arc
							(start 0.2794 -0.1778)
							(mid 0.249642 -0.249642)
							(end 0.1778 -0.2794)
						)
					)
					(width 0)
					(fill yes)
				)
			)
		)
		(pad "2" smd custom
			(at 0 0.4445)
			(size 0.1397 0.1397)
			(layers "F.Cu" "F.Mask" "F.Paste")
			(net "SSD_PRSNT5")
			(options
				(clearance outline)
				(anchor circle)
			)
			(primitives
				(gr_poly
					(pts
						(arc
							(start -0.1778 -0.2794)
							(mid -0.249642 -0.249642)
							(end -0.2794 -0.1778)
						)
						(arc
							(start -0.2794 0.1778)
							(mid -0.249642 0.249642)
							(end -0.1778 0.2794)
						)
						(arc
							(start 0.1778 0.2794)
							(mid 0.249642 0.249642)
							(end 0.2794 0.1778)
						)
						(arc
							(start 0.2794 -0.1778)
							(mid 0.249642 -0.249642)
							(end 0.1778 -0.2794)
						)
					)
					(width 0)
					(fill yes)
				)
			)
		)
	)
	(footprint ""
		(layer "F.Cu")
		(at 93.853 -202.184)
		(property "Reference" "R9087"
			(at 0 0 0)
			(layer "F.SilkS")
			(hide yes)
			(effects
				(font
					(size 1.27 1.27)
				)
			)
		)
		(property "Value" "27R2F-GP"
			(at 0.064008 -3.993896 0)
			(unlocked yes)
			(layer "F.Fab")
			(hide yes)
			(effects
				(font
					(size 1.016 1.016)
					(thickness 0.1524)
				)
			)
		)
		(property "Device Type" "R402H16"
			(at 0.064008 -5.517896 0)
			(unlocked yes)
			(layer "F.Fab")
			(hide yes)
			(effects
				(font
					(size 1.016 1.016)
					(thickness 0.1524)
				)
			)
		)
		(duplicate_pad_numbers_are_jumpers no)
		(fp_line
			(start -0.508 -0.9398)
			(end -0.508 0.9398)
			(stroke
				(width 0.1524)
				(type default)
			)
			(layer "F.SilkS")
		)
		(fp_line
			(start 0.508 -0.9398)
			(end -0.508 -0.9398)
			(stroke
				(width 0.1524)
				(type default)
			)
			(layer "F.SilkS")
		)
		(fp_rect
			(start -0.508 0.9398)
			(end 0.508 -0.9398)
			(stroke
				(width 0)
				(type default)
			)
			(fill no)
			(layer "F.CrtYd")
		)
		(fp_rect
			(start -0.508 0.9398)
			(end 0.508 -0.9398)
			(stroke
				(width 0)
				(type default)
			)
			(fill no)
			(layer "F.Fab")
		)
		(pad "1" smd custom
			(at 0 -0.4445)
			(size 0.1397 0.1397)
			(layers "F.Cu" "F.Mask" "F.Paste")
			(net "PE_CLK_100M_DR4_2_R_P")
			(options
				(clearance outline)
				(anchor circle)
			)
			(primitives
				(gr_poly
					(pts
						(arc
							(start -0.1778 -0.2794)
							(mid -0.249642 -0.249642)
							(end -0.2794 -0.1778)
						)
						(arc
							(start -0.2794 0.1778)
							(mid -0.249642 0.249642)
							(end -0.1778 0.2794)
						)
						(arc
							(start 0.1778 0.2794)
							(mid 0.249642 0.249642)
							(end 0.2794 0.1778)
						)
						(arc
							(start 0.2794 -0.1778)
							(mid 0.249642 -0.249642)
							(end 0.1778 -0.2794)
						)
					)
					(width 0)
					(fill yes)
				)
			)
		)
		(pad "2" smd custom
			(at 0 0.4445)
			(size 0.1397 0.1397)
			(layers "F.Cu" "F.Mask" "F.Paste")
			(net "PE_CLK100M_DR4_2_P")
			(options
				(clearance outline)
				(anchor circle)
			)
			(primitives
				(gr_poly
					(pts
						(arc
							(start -0.1778 -0.2794)
							(mid -0.249642 -0.249642)
							(end -0.2794 -0.1778)
						)
						(arc
							(start -0.2794 0.1778)
							(mid -0.249642 0.249642)
							(end -0.1778 0.2794)
						)
						(arc
							(start 0.1778 0.2794)
							(mid 0.249642 0.249642)
							(end 0.2794 0.1778)
						)
						(arc
							(start 0.2794 -0.1778)
							(mid 0.249642 -0.249642)
							(end 0.1778 -0.2794)
						)
					)
					(width 0)
					(fill yes)
				)
			)
		)
	)
	(footprint ""
		(layer "F.Cu")
		(at 94.234 -297.942)
		(property "Reference" "C8849"
			(at 0 0 0)
			(layer "F.SilkS")
			(hide yes)
			(effects
				(font
					(size 1.27 1.27)
				)
			)
		)
		(property "Value" "SCD1U16V2KX-3GP"
			(at 1.1811 -2.7051 0)
			(unlocked yes)
			(layer "F.Fab")
			(hide yes)
			(effects
				(font
					(size 1.016 1.016)
					(thickness 0.1524)
				)
			)
		)
		(property "Device Type" "C402H22"
			(at 1.1811 -4.2291 0)
			(unlocked yes)
			(layer "F.Fab")
			(hide yes)
			(effects
				(font
					(size 1.016 1.016)
					(thickness 0.1524)
				)
			)
		)
		(duplicate_pad_numbers_are_jumpers no)
		(fp_rect
			(start -0.4318 0.9525)
			(end 0.4318 -0.9525)
			(stroke
				(width 0)
				(type default)
			)
			(fill no)
			(layer "F.CrtYd")
		)
		(fp_rect
			(start -0.4318 0.9525)
			(end 0.4318 -0.9525)
			(stroke
				(width 0)
				(type default)
			)
			(fill no)
			(layer "F.Fab")
		)
		(pad "1" smd custom
			(at 0 -0.4445)
			(size 0.1524 0.1524)
			(layers "F.Cu" "F.Mask" "F.Paste")
			(net "VDD_IO_2")
			(options
				(clearance outline)
				(anchor circle)
			)
			(primitives
				(gr_poly
					(pts
						(arc
							(start 0.3048 -0.2032)
							(mid 0.275042 -0.275042)
							(end 0.2032 -0.3048)
						)
						(arc
							(start -0.2032 -0.3048)
							(mid -0.275042 -0.275042)
							(end -0.3048 -0.2032)
						)
						(arc
							(start -0.3048 0.2032)
							(mid -0.275042 0.275042)
							(end -0.2032 0.3048)
						)
						(arc
							(start 0.2032 0.3048)
							(mid 0.275042 0.275042)
							(end 0.3048 0.2032)
						)
					)
					(width 0)
					(fill yes)
				)
			)
		)
		(pad "2" smd custom
			(at 0 0.4445)
			(size 0.1524 0.1524)
			(layers "F.Cu" "F.Mask" "F.Paste")
			(net "GND")
			(options
				(clearance outline)
				(anchor circle)
			)
			(primitives
				(gr_poly
					(pts
						(arc
							(start 0.3048 -0.2032)
							(mid 0.275042 -0.275042)
							(end 0.2032 -0.3048)
						)
						(arc
							(start -0.2032 -0.3048)
							(mid -0.275042 -0.275042)
							(end -0.3048 -0.2032)
						)
						(arc
							(start -0.3048 0.2032)
							(mid -0.275042 0.275042)
							(end -0.2032 0.3048)
						)
						(arc
							(start 0.2032 0.3048)
							(mid 0.275042 0.275042)
							(end 0.3048 0.2032)
						)
					)
					(width 0)
					(fill yes)
				)
			)
		)
	)
	(footprint ""
		(layer "F.Cu")
		(at 32.2072 -215.2142 180)
		(property "Reference" "SR1115"
			(at 0 0 180)
			(layer "F.SilkS")
			(hide yes)
			(effects
				(font
					(size 1.27 1.27)
				)
			)
		)
		(property "Value" "4K7R2F-GP"
			(at 0.064008 -3.993896 180)
			(unlocked yes)
			(layer "F.Fab")
			(hide yes)
			(effects
				(font
					(size 1.016 1.016)
					(thickness 0.1524)
				)
			)
		)
		(property "Device Type" "R402H16"
			(at 0.064008 -5.517896 180)
			(unlocked yes)
			(layer "F.Fab")
			(hide yes)
			(effects
				(font
					(size 1.016 1.016)
					(thickness 0.1524)
				)
			)
		)
		(duplicate_pad_numbers_are_jumpers no)
		(fp_line
			(start 0.508 -0.9398)
			(end -0.508 -0.9398)
			(stroke
				(width 0.1524)
				(type default)
			)
			(layer "F.SilkS")
		)
		(fp_line
			(start -0.508 -0.9398)
			(end -0.508 0.9398)
			(stroke
				(width 0.1524)
				(type default)
			)
			(layer "F.SilkS")
		)
		(fp_rect
			(start -0.508 0.9398)
			(end 0.508 -0.9398)
			(stroke
				(width 0)
				(type default)
			)
			(fill no)
			(layer "F.CrtYd")
		)
		(fp_rect
			(start -0.508 0.9398)
			(end 0.508 -0.9398)
			(stroke
				(width 0)
				(type default)
			)
			(fill no)
			(layer "F.Fab")
		)
		(pad "1" smd custom
			(at 0 -0.4445 180)
			(size 0.1397 0.1397)
			(layers "F.Cu" "F.Mask" "F.Paste")
			(net "P3V3")
			(options
				(clearance outline)
				(anchor circle)
			)
			(primitives
				(gr_poly
					(pts
						(arc
							(start -0.1778 -0.2794)
							(mid -0.249642 -0.249642)
							(end -0.2794 -0.1778)
						)
						(arc
							(start -0.2794 0.1778)
							(mid -0.249642 0.249642)
							(end -0.1778 0.2794)
						)
						(arc
							(start 0.1778 0.2794)
							(mid 0.249642 0.249642)
							(end 0.2794 0.1778)
						)
						(arc
							(start 0.2794 -0.1778)
							(mid 0.249642 -0.249642)
							(end 0.1778 -0.2794)
						)
					)
					(width 0)
					(fill yes)
				)
			)
		)
		(pad "2" smd custom
			(at 0 0.4445 180)
			(size 0.1397 0.1397)
			(layers "F.Cu" "F.Mask" "F.Paste")
			(net "DUALPORTEN#12")
			(options
				(clearance outline)
				(anchor circle)
			)
			(primitives
				(gr_poly
					(pts
						(arc
							(start -0.1778 -0.2794)
							(mid -0.249642 -0.249642)
							(end -0.2794 -0.1778)
						)
						(arc
							(start -0.2794 0.1778)
							(mid -0.249642 0.249642)
							(end -0.1778 0.2794)
						)
						(arc
							(start 0.1778 0.2794)
							(mid 0.249642 0.249642)
							(end 0.2794 0.1778)
						)
						(arc
							(start 0.2794 -0.1778)
							(mid 0.249642 -0.249642)
							(end 0.1778 -0.2794)
						)
					)
					(width 0)
					(fill yes)
				)
			)
		)
	)
	(footprint ""
		(layer "F.Cu")
		(at 99.187 -115.062)
		(property "Reference" "R9604"
			(at 0 0 0)
			(layer "F.SilkS")
			(hide yes)
			(effects
				(font
					(size 1.27 1.27)
				)
			)
		)
		(property "Value" "10R2F-L-GP"
			(at 0.064008 -3.993896 0)
			(unlocked yes)
			(layer "F.Fab")
			(hide yes)
			(effects
				(font
					(size 1.016 1.016)
					(thickness 0.1524)
				)
			)
		)
		(property "Device Type" "R402H14"
			(at 0.064008 -5.517896 0)
			(unlocked yes)
			(layer "F.Fab")
			(hide yes)
			(effects
				(font
					(size 1.016 1.016)
					(thickness 0.1524)
				)
			)
		)
		(duplicate_pad_numbers_are_jumpers no)
		(fp_line
			(start -0.508 -0.9398)
			(end -0.508 0.9398)
			(stroke
				(width 0.1524)
				(type default)
			)
			(layer "F.SilkS")
		)
		(fp_line
			(start 0.508 -0.9398)
			(end -0.508 -0.9398)
			(stroke
				(width 0.1524)
				(type default)
			)
			(layer "F.SilkS")
		)
		(fp_rect
			(start -0.508 0.9398)
			(end 0.508 -0.9398)
			(stroke
				(width 0)
				(type default)
			)
			(fill no)
			(layer "F.CrtYd")
		)
		(fp_rect
			(start -0.508 0.9398)
			(end 0.508 -0.9398)
			(stroke
				(width 0)
				(type default)
			)
			(fill no)
			(layer "F.Fab")
		)
		(pad "1" smd custom
			(at 0 -0.4445)
			(size 0.1397 0.1397)
			(layers "F.Cu" "F.Mask" "F.Paste")
			(net "SSD_PRSNT_NET8")
			(options
				(clearance outline)
				(anchor circle)
			)
			(primitives
				(gr_poly
					(pts
						(arc
							(start -0.1778 -0.2794)
							(mid -0.249642 -0.249642)
							(end -0.2794 -0.1778)
						)
						(arc
							(start -0.2794 0.1778)
							(mid -0.249642 0.249642)
							(end -0.1778 0.2794)
						)
						(arc
							(start 0.1778 0.2794)
							(mid 0.249642 0.249642)
							(end 0.2794 0.1778)
						)
						(arc
							(start 0.2794 -0.1778)
							(mid 0.249642 -0.249642)
							(end 0.1778 -0.2794)
						)
					)
					(width 0)
					(fill yes)
				)
			)
		)
		(pad "2" smd custom
			(at 0 0.4445)
			(size 0.1397 0.1397)
			(layers "F.Cu" "F.Mask" "F.Paste")
			(net "SSD_PRSNT8")
			(options
				(clearance outline)
				(anchor circle)
			)
			(primitives
				(gr_poly
					(pts
						(arc
							(start -0.1778 -0.2794)
							(mid -0.249642 -0.249642)
							(end -0.2794 -0.1778)
						)
						(arc
							(start -0.2794 0.1778)
							(mid -0.249642 0.249642)
							(end -0.1778 0.2794)
						)
						(arc
							(start 0.1778 0.2794)
							(mid 0.249642 0.249642)
							(end 0.2794 0.1778)
						)
						(arc
							(start 0.2794 -0.1778)
							(mid 0.249642 -0.249642)
							(end 0.1778 -0.2794)
						)
					)
					(width 0)
					(fill yes)
				)
			)
		)
	)
	(footprint ""
		(layer "F.Cu")
		(at 229.67696 -138.11885)
		(property "Reference" "C9521"
			(at 0 0 0)
			(layer "F.SilkS")
			(hide yes)
			(effects
				(font
					(size 1.27 1.27)
				)
			)
		)
		(property "Value" "SCD1U16V2KX-3GP"
			(at 1.1811 -2.7051 0)
			(unlocked yes)
			(layer "F.Fab")
			(hide yes)
			(effects
				(font
					(size 1.016 1.016)
					(thickness 0.1524)
				)
			)
		)
		(property "Device Type" "C402H22"
			(at 1.1811 -4.2291 0)
			(unlocked yes)
			(layer "F.Fab")
			(hide yes)
			(effects
				(font
					(size 1.016 1.016)
					(thickness 0.1524)
				)
			)
		)
		(duplicate_pad_numbers_are_jumpers no)
		(fp_rect
			(start -0.4318 0.9525)
			(end 0.4318 -0.9525)
			(stroke
				(width 0)
				(type default)
			)
			(fill no)
			(layer "F.CrtYd")
		)
		(fp_rect
			(start -0.4318 0.9525)
			(end 0.4318 -0.9525)
			(stroke
				(width 0)
				(type default)
			)
			(fill no)
			(layer "F.Fab")
		)
		(pad "1" smd custom
			(at 0 -0.4445)
			(size 0.1524 0.1524)
			(layers "F.Cu" "F.Mask" "F.Paste")
			(net "P3V3")
			(options
				(clearance outline)
				(anchor circle)
			)
			(primitives
				(gr_poly
					(pts
						(arc
							(start 0.3048 -0.2032)
							(mid 0.275042 -0.275042)
							(end 0.2032 -0.3048)
						)
						(arc
							(start -0.2032 -0.3048)
							(mid -0.275042 -0.275042)
							(end -0.3048 -0.2032)
						)
						(arc
							(start -0.3048 0.2032)
							(mid -0.275042 0.275042)
							(end -0.2032 0.3048)
						)
						(arc
							(start 0.2032 0.3048)
							(mid 0.275042 0.275042)
							(end 0.3048 0.2032)
						)
					)
					(width 0)
					(fill yes)
				)
			)
		)
		(pad "2" smd custom
			(at 0 0.4445)
			(size 0.1524 0.1524)
			(layers "F.Cu" "F.Mask" "F.Paste")
			(net "GND")
			(options
				(clearance outline)
				(anchor circle)
			)
			(primitives
				(gr_poly
					(pts
						(arc
							(start 0.3048 -0.2032)
							(mid 0.275042 -0.275042)
							(end 0.2032 -0.3048)
						)
						(arc
							(start -0.2032 -0.3048)
							(mid -0.275042 -0.275042)
							(end -0.3048 -0.2032)
						)
						(arc
							(start -0.3048 0.2032)
							(mid -0.275042 0.275042)
							(end -0.2032 0.3048)
						)
						(arc
							(start 0.2032 0.3048)
							(mid 0.275042 0.275042)
							(end 0.3048 0.2032)
						)
					)
					(width 0)
					(fill yes)
				)
			)
		)
	)
)
